(kicad_pcb
	(version 20260206)
	(generator "pcbnew")
	(generator_version "10.0")
	(general
		(thickness 1.6)
		(legacy_teardrops no)
	)
	(paper "A4")
	(title_block
		(title "Bryce Canyon_SCC_16316-1_OCP.brd")
		(comment 1 "Bryce Canyon / footprints 1448-1455 of 1561")
	)
	(layers
		(0 "F.Cu" signal "TOP")
		(4 "In1.Cu" signal "L2GND")
		(6 "In2.Cu" signal "L3")
		(8 "In3.Cu" signal "L4VCC")
		(10 "In4.Cu" signal "L5VCC")
		(12 "In5.Cu" signal "L6")
		(14 "In6.Cu" signal "L7GND")
		(2 "B.Cu" signal "BOTTOM")
		(9 "F.Adhes" user "F.Adhesive")
		(11 "B.Adhes" user "B.Adhesive")
		(13 "F.Paste" user "Package Geometry/Pastemask Top")
		(15 "B.Paste" user "Package Geometry/Pastemask Bottom")
		(5 "F.SilkS" user "Ref Des/Silkscreen Top")
		(7 "B.SilkS" user "Ref Des/Silkscreen Bottom")
		(1 "F.Mask" user "Board Geometry/Soldermask Top")
		(3 "B.Mask" user "Board Geometry/Soldermask Bottom")
		(17 "Dwgs.User" user "User.Drawings")
		(19 "Cmts.User" user "User.Comments")
		(21 "Eco1.User" user "User.Eco1")
		(23 "Eco2.User" user "User.Eco2")
		(25 "Edge.Cuts" user "Board Geometry/Outline")
		(27 "Margin" user)
		(31 "F.CrtYd" user "Package Geometry/Place Bound Top")
		(29 "B.CrtYd" user "Package Geometry/Place Bound Bottom")
		(35 "F.Fab" user "Ref Des/Assembly Top")
		(33 "B.Fab" user "Ref Des/Assembly Bottom")
	)
	(footprint ""
		(layer "B.Cu")
		(at 96.497394 -50.950368 90)
		(property "Reference" "C90"
			(at 0 0 90)
			(layer "B.SilkS")
			(hide yes)
			(effects
				(font
					(size 1.27 1.27)
				)
				(justify mirror)
			)
		)
		(property "Value" "SCD01U16V1KX-GP"
			(at 2.8321 -1.7399 90)
			(unlocked yes)
			(layer "B.Fab")
			(hide yes)
			(effects
				(font
					(size 1.016 1.016)
					(thickness 0.1524)
				)
				(justify mirror)
			)
		)
		(property "Device Type" "C0201H13"
			(at 2.8321 -3.2639 90)
			(unlocked yes)
			(layer "B.Fab")
			(hide yes)
			(effects
				(font
					(size 1.016 1.016)
					(thickness 0.1524)
				)
				(justify mirror)
			)
		)
		(duplicate_pad_numbers_are_jumpers no)
		(fp_rect
			(start 0.2794 0.6477)
			(end -0.2794 -0.6477)
			(stroke
				(width 0)
				(type default)
			)
			(fill no)
			(layer "B.CrtYd")
		)
		(fp_rect
			(start 0.2794 0.6477)
			(end -0.2794 -0.6477)
			(stroke
				(width 0)
				(type default)
			)
			(fill no)
			(layer "B.Fab")
		)
		(pad "1" smd custom
			(at 0 -0.2794 270)
			(size 0.0762 0.0762)
			(layers "B.Cu" "B.Mask" "B.Paste")
			(net "PHY_DPB_TO_SCC_15_DN")
			(options
				(clearance outline)
				(anchor circle)
			)
			(primitives
				(gr_poly
					(pts
						(arc
							(start 0.1524 0.127)
							(mid 0.137521 0.162921)
							(end 0.1016 0.1778)
						)
						(arc
							(start -0.1016 0.1778)
							(mid -0.137521 0.162921)
							(end -0.1524 0.127)
						)
						(arc
							(start -0.1524 -0.127)
							(mid -0.137521 -0.162921)
							(end -0.1016 -0.1778)
						)
						(arc
							(start 0.1016 -0.1778)
							(mid 0.137521 -0.162921)
							(end 0.1524 -0.127)
						)
					)
					(width 0)
					(fill yes)
				)
			)
		)
		(pad "2" smd custom
			(at 0 0.2794 270)
			(size 0.0762 0.0762)
			(layers "B.Cu" "B.Mask" "B.Paste")
			(net "PHY_DPB_TO_SCC_C_15_DN")
			(options
				(clearance outline)
				(anchor circle)
			)
			(primitives
				(gr_poly
					(pts
						(arc
							(start 0.1524 0.127)
							(mid 0.137521 0.162921)
							(end 0.1016 0.1778)
						)
						(arc
							(start -0.1016 0.1778)
							(mid -0.137521 0.162921)
							(end -0.1524 0.127)
						)
						(arc
							(start -0.1524 -0.127)
							(mid -0.137521 -0.162921)
							(end -0.1016 -0.1778)
						)
						(arc
							(start 0.1016 -0.1778)
							(mid 0.137521 -0.162921)
							(end 0.1524 -0.127)
						)
					)
					(width 0)
					(fill yes)
				)
			)
		)
	)
	(footprint ""
		(layer "B.Cu")
		(at 128.2192 -40.8686 180)
		(property "Reference" "C32"
			(at 0 0 0)
			(layer "B.SilkS")
			(hide yes)
			(effects
				(font
					(size 1.27 1.27)
				)
				(justify mirror)
			)
		)
		(property "Value" "SCD01U16V1KX-GP"
			(at 2.8321 -1.7399 180)
			(unlocked yes)
			(layer "B.Fab")
			(hide yes)
			(effects
				(font
					(size 1.016 1.016)
					(thickness 0.1524)
				)
				(justify mirror)
			)
		)
		(property "Device Type" "C0201H13"
			(at 2.8321 -3.2639 180)
			(unlocked yes)
			(layer "B.Fab")
			(hide yes)
			(effects
				(font
					(size 1.016 1.016)
					(thickness 0.1524)
				)
				(justify mirror)
			)
		)
		(duplicate_pad_numbers_are_jumpers no)
		(fp_rect
			(start 0.2794 0.6477)
			(end -0.2794 -0.6477)
			(stroke
				(width 0)
				(type default)
			)
			(fill no)
			(layer "B.CrtYd")
		)
		(fp_rect
			(start 0.2794 0.6477)
			(end -0.2794 -0.6477)
			(stroke
				(width 0)
				(type default)
			)
			(fill no)
			(layer "B.Fab")
		)
		(pad "1" smd custom
			(at 0 -0.2794)
			(size 0.0762 0.0762)
			(layers "B.Cu" "B.Mask" "B.Paste")
			(net "PHY_DPB_TO_SCC_28_DN")
			(options
				(clearance outline)
				(anchor circle)
			)
			(primitives
				(gr_poly
					(pts
						(arc
							(start 0.1524 0.127)
							(mid 0.137521 0.162921)
							(end 0.1016 0.1778)
						)
						(arc
							(start -0.1016 0.1778)
							(mid -0.137521 0.162921)
							(end -0.1524 0.127)
						)
						(arc
							(start -0.1524 -0.127)
							(mid -0.137521 -0.162921)
							(end -0.1016 -0.1778)
						)
						(arc
							(start 0.1016 -0.1778)
							(mid 0.137521 -0.162921)
							(end 0.1524 -0.127)
						)
					)
					(width 0)
					(fill yes)
				)
			)
		)
		(pad "2" smd custom
			(at 0 0.2794)
			(size 0.0762 0.0762)
			(layers "B.Cu" "B.Mask" "B.Paste")
			(net "PHY_DPB_TO_SCC_C_28_DN")
			(options
				(clearance outline)
				(anchor circle)
			)
			(primitives
				(gr_poly
					(pts
						(arc
							(start 0.1524 0.127)
							(mid 0.137521 0.162921)
							(end 0.1016 0.1778)
						)
						(arc
							(start -0.1016 0.1778)
							(mid -0.137521 0.162921)
							(end -0.1524 0.127)
						)
						(arc
							(start -0.1524 -0.127)
							(mid -0.137521 -0.162921)
							(end -0.1016 -0.1778)
						)
						(arc
							(start 0.1016 -0.1778)
							(mid 0.137521 -0.162921)
							(end 0.1524 -0.127)
						)
					)
					(width 0)
					(fill yes)
				)
			)
		)
	)
	(footprint ""
		(layer "B.Cu")
		(at 93.311472 -71.192898)
		(property "Reference" "C197"
			(at 0 0 0)
			(layer "B.SilkS")
			(hide yes)
			(effects
				(font
					(size 1.27 1.27)
				)
				(justify mirror)
			)
		)
		(property "Value" "SC10U6D3V2MX-GP-U"
			(at 1.524 -1.905 0)
			(unlocked yes)
			(layer "B.Fab")
			(hide yes)
			(effects
				(font
					(size 1.016 1.016)
					(thickness 0.1524)
				)
				(justify mirror)
			)
		)
		(property "Device Type" "C402-TO0D2H28"
			(at 1.524 -3.429 0)
			(unlocked yes)
			(layer "B.Fab")
			(hide yes)
			(effects
				(font
					(size 1.016 1.016)
					(thickness 0.1524)
				)
				(justify mirror)
			)
		)
		(duplicate_pad_numbers_are_jumpers no)
		(fp_rect
			(start 0.4826 0.889)
			(end -0.4826 -0.889)
			(stroke
				(width 0)
				(type default)
			)
			(fill no)
			(layer "B.CrtYd")
		)
		(fp_rect
			(start 0.4826 0.889)
			(end -0.4826 -0.889)
			(stroke
				(width 0)
				(type default)
			)
			(fill no)
			(layer "B.Fab")
		)
		(pad "1" smd custom
			(at 0 -0.4572 180)
			(size 0.1524 0.1524)
			(layers "B.Cu" "B.Mask" "B.Paste")
			(net "SYSPLL_VDDA18")
			(options
				(clearance outline)
				(anchor circle)
			)
			(primitives
				(gr_poly
					(pts
						(arc
							(start -0.254 -0.3048)
							(mid -0.325842 -0.275042)
							(end -0.3556 -0.2032)
						)
						(arc
							(start -0.3556 0.2032)
							(mid -0.325842 0.275042)
							(end -0.254 0.3048)
						)
						(arc
							(start 0.254 0.3048)
							(mid 0.325842 0.275042)
							(end 0.3556 0.2032)
						)
						(arc
							(start 0.3556 -0.2032)
							(mid 0.325842 -0.275042)
							(end 0.254 -0.3048)
						)
					)
					(width 0)
					(fill yes)
				)
			)
		)
		(pad "2" smd custom
			(at 0 0.4572 180)
			(size 0.1524 0.1524)
			(layers "B.Cu" "B.Mask" "B.Paste")
			(net "GND")
			(options
				(clearance outline)
				(anchor circle)
			)
			(primitives
				(gr_poly
					(pts
						(arc
							(start -0.254 -0.3048)
							(mid -0.325842 -0.275042)
							(end -0.3556 -0.2032)
						)
						(arc
							(start -0.3556 0.2032)
							(mid -0.325842 0.275042)
							(end -0.254 0.3048)
						)
						(arc
							(start 0.254 0.3048)
							(mid 0.325842 0.275042)
							(end 0.3556 0.2032)
						)
						(arc
							(start 0.3556 -0.2032)
							(mid 0.325842 -0.275042)
							(end 0.254 -0.3048)
						)
					)
					(width 0)
					(fill yes)
				)
			)
		)
	)
	(footprint ""
		(layer "B.Cu")
		(at 159.40278 -116.00942 180)
		(property "Reference" "C607"
			(at 0 0 0)
			(layer "B.SilkS")
			(hide yes)
			(effects
				(font
					(size 1.27 1.27)
				)
				(justify mirror)
			)
		)
		(property "Value" "SC4D7U25V5KX-1-GP"
			(at 0.0762 -6.1214 180)
			(unlocked yes)
			(layer "B.Fab")
			(hide yes)
			(effects
				(font
					(size 1.016 1.016)
					(thickness 0.1524)
				)
				(justify mirror)
			)
		)
		(property "Device Type" "C805H58"
			(at 0.0762 -8.1534 180)
			(unlocked yes)
			(layer "B.Fab")
			(hide yes)
			(effects
				(font
					(size 1.016 1.016)
					(thickness 0.1524)
				)
				(justify mirror)
			)
		)
		(duplicate_pad_numbers_are_jumpers no)
		(fp_line
			(start -0.635 0)
			(end 0.635 0)
			(stroke
				(width 0.508)
				(type default)
			)
			(layer "B.SilkS")
		)
		(fp_rect
			(start 0.9652 1.778)
			(end -0.9652 -1.778)
			(stroke
				(width 0)
				(type default)
			)
			(fill no)
			(layer "B.CrtYd")
		)
		(fp_poly
			(pts
				(xy 0.9652 -1.778) (xy -0.9652 -1.778) (xy -0.9652 1.778) (xy 0.9652 1.778)
			)
			(stroke
				(width 0)
				(type default)
			)
			(fill no)
			(layer "B.Fab")
		)
		(pad "1" smd rect
			(at 0 -0.9652)
			(size 1.397 1.143)
			(layers "B.Cu" "B.Mask" "B.Paste")
			(net "P12V_STBY_VDD_U11")
		)
		(pad "2" smd rect
			(at 0 0.9652)
			(size 1.397 1.143)
			(layers "B.Cu" "B.Mask" "B.Paste")
			(net "GND")
		)
	)
	(footprint ""
		(layer "B.Cu")
		(at 137.4648 -69.9008 -90)
		(property "Reference" "C15"
			(at 0 0 90)
			(layer "B.SilkS")
			(hide yes)
			(effects
				(font
					(size 1.27 1.27)
				)
				(justify mirror)
			)
		)
		(property "Value" "SCD01U16V1KX-GP"
			(at 2.8321 -1.7399 270)
			(unlocked yes)
			(layer "B.Fab")
			(hide yes)
			(effects
				(font
					(size 1.016 1.016)
					(thickness 0.1524)
				)
				(justify mirror)
			)
		)
		(property "Device Type" "C0201H13"
			(at 2.8321 -3.2639 270)
			(unlocked yes)
			(layer "B.Fab")
			(hide yes)
			(effects
				(font
					(size 1.016 1.016)
					(thickness 0.1524)
				)
				(justify mirror)
			)
		)
		(duplicate_pad_numbers_are_jumpers no)
		(fp_rect
			(start 0.2794 0.6477)
			(end -0.2794 -0.6477)
			(stroke
				(width 0)
				(type default)
			)
			(fill no)
			(layer "B.CrtYd")
		)
		(fp_rect
			(start 0.2794 0.6477)
			(end -0.2794 -0.6477)
			(stroke
				(width 0)
				(type default)
			)
			(fill no)
			(layer "B.Fab")
		)
		(pad "1" smd custom
			(at 0 -0.2794 90)
			(size 0.0762 0.0762)
			(layers "B.Cu" "B.Mask" "B.Paste")
			(net "PHY_DPB_TO_SCC_4_DP")
			(options
				(clearance outline)
				(anchor circle)
			)
			(primitives
				(gr_poly
					(pts
						(arc
							(start 0.1524 0.127)
							(mid 0.137521 0.162921)
							(end 0.1016 0.1778)
						)
						(arc
							(start -0.1016 0.1778)
							(mid -0.137521 0.162921)
							(end -0.1524 0.127)
						)
						(arc
							(start -0.1524 -0.127)
							(mid -0.137521 -0.162921)
							(end -0.1016 -0.1778)
						)
						(arc
							(start 0.1016 -0.1778)
							(mid 0.137521 -0.162921)
							(end 0.1524 -0.127)
						)
					)
					(width 0)
					(fill yes)
				)
			)
		)
		(pad "2" smd custom
			(at 0 0.2794 90)
			(size 0.0762 0.0762)
			(layers "B.Cu" "B.Mask" "B.Paste")
			(net "PHY_DPB_TO_SCC_C_4_DP")
			(options
				(clearance outline)
				(anchor circle)
			)
			(primitives
				(gr_poly
					(pts
						(arc
							(start 0.1524 0.127)
							(mid 0.137521 0.162921)
							(end 0.1016 0.1778)
						)
						(arc
							(start -0.1016 0.1778)
							(mid -0.137521 0.162921)
							(end -0.1524 0.127)
						)
						(arc
							(start -0.1524 -0.127)
							(mid -0.137521 -0.162921)
							(end -0.1016 -0.1778)
						)
						(arc
							(start 0.1016 -0.1778)
							(mid 0.137521 -0.162921)
							(end 0.1524 -0.127)
						)
					)
					(width 0)
					(fill yes)
				)
			)
		)
	)
	(footprint ""
		(layer "B.Cu")
		(at 166.335964 -8.6614 -90)
		(property "Reference" "U50"
			(at 0 0 90)
			(layer "B.SilkS")
			(hide yes)
			(effects
				(font
					(size 1.27 1.27)
				)
				(justify mirror)
			)
		)
		(property "Value" "SNLVC1G126DCKR-GP"
			(at 2.3368 -8.6868 270)
			(unlocked yes)
			(layer "B.Fab")
			(hide yes)
			(effects
				(font
					(size 1.016 1.016)
					(thickness 0.1524)
				)
				(justify mirror)
			)
		)
		(property "Device Type" "SC70-5H44"
			(at 2.3114 -10.414 270)
			(unlocked yes)
			(layer "B.Fab")
			(hide yes)
			(effects
				(font
					(size 1.016 1.016)
					(thickness 0.1524)
				)
				(justify mirror)
			)
		)
		(duplicate_pad_numbers_are_jumpers no)
		(fp_line
			(start -1.27 1.7018)
			(end 1.27 1.7018)
			(stroke
				(width 0.1524)
				(type default)
			)
			(layer "B.SilkS")
		)
		(fp_line
			(start 1.27 1.7018)
			(end 1.27 -1.7018)
			(stroke
				(width 0.1524)
				(type default)
			)
			(layer "B.SilkS")
		)
		(fp_line
			(start -1.27 -1.7018)
			(end -1.27 1.7018)
			(stroke
				(width 0.1524)
				(type default)
			)
			(layer "B.SilkS")
		)
		(fp_line
			(start 1.27 -1.7018)
			(end -1.27 -1.7018)
			(stroke
				(width 0.1524)
				(type default)
			)
			(layer "B.SilkS")
		)
		(fp_line
			(start -1.3843 -1.8034)
			(end -1.3843 -1.1176)
			(stroke
				(width 0.3302)
				(type default)
			)
			(layer "B.SilkS")
		)
		(fp_line
			(start -0.6604 -1.8034)
			(end -1.3843 -1.8034)
			(stroke
				(width 0.3302)
				(type default)
			)
			(layer "B.SilkS")
		)
		(fp_rect
			(start 1.524 1.9558)
			(end -1.524 -1.9558)
			(stroke
				(width 0)
				(type default)
			)
			(fill no)
			(layer "B.CrtYd")
		)
		(fp_poly
			(pts
				(xy 1.524 -1.9558) (xy -1.524 -1.9558) (xy -1.524 1.9558) (xy 1.524 1.9558)
			)
			(stroke
				(width 0)
				(type default)
			)
			(fill no)
			(layer "B.Fab")
		)
		(pad "1" smd rect
			(at -0.65024 -0.8255 90)
			(size 0.4064 1.2192)
			(layers "B.Cu" "B.Mask" "B.Paste")
			(net "U50_OE")
		)
		(pad "2" smd rect
			(at 0 -0.8255 90)
			(size 0.4064 1.2192)
			(layers "B.Cu" "B.Mask" "B.Paste")
			(net "SCC_RESET_N")
		)
		(pad "3" smd rect
			(at 0.65024 -0.8255 90)
			(size 0.4064 1.2192)
			(layers "B.Cu" "B.Mask" "B.Paste")
			(net "GND")
		)
		(pad "4" smd rect
			(at 0.65024 0.8255 90)
			(size 0.4064 1.2192)
			(layers "B.Cu" "B.Mask" "B.Paste")
			(net "SCC_RESET_BUF_N")
		)
		(pad "5" smd rect
			(at -0.65024 0.8255 90)
			(size 0.4064 1.2192)
			(layers "B.Cu" "B.Mask" "B.Paste")
			(net "P3V3")
		)
	)
	(footprint ""
		(layer "B.Cu")
		(at 105.5116 -79.6036)
		(property "Reference" "C156"
			(at 0 0 0)
			(layer "B.SilkS")
			(hide yes)
			(effects
				(font
					(size 1.27 1.27)
				)
				(justify mirror)
			)
		)
		(property "Value" "SCD1U6D3V1KX-GP"
			(at 2.8321 -1.7399 0)
			(unlocked yes)
			(layer "B.Fab")
			(hide yes)
			(effects
				(font
					(size 1.016 1.016)
					(thickness 0.1524)
				)
				(justify mirror)
			)
		)
		(property "Device Type" "C0201H13"
			(at 2.8321 -3.2639 0)
			(unlocked yes)
			(layer "B.Fab")
			(hide yes)
			(effects
				(font
					(size 1.016 1.016)
					(thickness 0.1524)
				)
				(justify mirror)
			)
		)
		(duplicate_pad_numbers_are_jumpers no)
		(fp_rect
			(start 0.2794 0.6477)
			(end -0.2794 -0.6477)
			(stroke
				(width 0)
				(type default)
			)
			(fill no)
			(layer "B.CrtYd")
		)
		(fp_rect
			(start 0.2794 0.6477)
			(end -0.2794 -0.6477)
			(stroke
				(width 0)
				(type default)
			)
			(fill no)
			(layer "B.Fab")
		)
		(pad "1" smd custom
			(at 0 -0.2794 180)
			(size 0.0762 0.0762)
			(layers "B.Cu" "B.Mask" "B.Paste")
			(net "P1V8_E")
			(options
				(clearance outline)
				(anchor circle)
			)
			(primitives
				(gr_poly
					(pts
						(arc
							(start 0.1524 0.127)
							(mid 0.137521 0.162921)
							(end 0.1016 0.1778)
						)
						(arc
							(start -0.1016 0.1778)
							(mid -0.137521 0.162921)
							(end -0.1524 0.127)
						)
						(arc
							(start -0.1524 -0.127)
							(mid -0.137521 -0.162921)
							(end -0.1016 -0.1778)
						)
						(arc
							(start 0.1016 -0.1778)
							(mid 0.137521 -0.162921)
							(end 0.1524 -0.127)
						)
					)
					(width 0)
					(fill yes)
				)
			)
		)
		(pad "2" smd custom
			(at 0 0.2794 180)
			(size 0.0762 0.0762)
			(layers "B.Cu" "B.Mask" "B.Paste")
			(net "GND")
			(options
				(clearance outline)
				(anchor circle)
			)
			(primitives
				(gr_poly
					(pts
						(arc
							(start 0.1524 0.127)
							(mid 0.137521 0.162921)
							(end 0.1016 0.1778)
						)
						(arc
							(start -0.1016 0.1778)
							(mid -0.137521 0.162921)
							(end -0.1524 0.127)
						)
						(arc
							(start -0.1524 -0.127)
							(mid -0.137521 -0.162921)
							(end -0.1016 -0.1778)
						)
						(arc
							(start 0.1016 -0.1778)
							(mid 0.137521 -0.162921)
							(end 0.1524 -0.127)
						)
					)
					(width 0)
					(fill yes)
				)
			)
		)
	)
	(footprint ""
		(layer "B.Cu")
		(at 138.17473 -121.94286 90)
		(property "Reference" "R1"
			(at 0 0 90)
			(layer "B.SilkS")
			(hide yes)
			(effects
				(font
					(size 1.27 1.27)
				)
				(justify mirror)
			)
		)
		(property "Value" "10KR2F-2-GP"
			(at -0.064008 -3.993896 90)
			(unlocked yes)
			(layer "B.Fab")
			(hide yes)
			(effects
				(font
					(size 1.016 1.016)
					(thickness 0.1524)
				)
				(justify mirror)
			)
		)
		(property "Device Type" "R402H16"
			(at -0.064008 -5.517896 90)
			(unlocked yes)
			(layer "B.Fab")
			(hide yes)
			(effects
				(font
					(size 1.016 1.016)
					(thickness 0.1524)
				)
				(justify mirror)
			)
		)
		(duplicate_pad_numbers_are_jumpers no)
		(fp_line
			(start 0.508 -0.9398)
			(end 0.508 0.9398)
			(stroke
				(width 0.1524)
				(type default)
			)
			(layer "B.SilkS")
		)
		(fp_line
			(start -0.508 -0.9398)
			(end 0.508 -0.9398)
			(stroke
				(width 0.1524)
				(type default)
			)
			(layer "B.SilkS")
		)
		(fp_rect
			(start 0.508 0.9398)
			(end -0.508 -0.9398)
			(stroke
				(width 0)
				(type default)
			)
			(fill no)
			(layer "B.CrtYd")
		)
		(fp_rect
			(start 0.508 0.9398)
			(end -0.508 -0.9398)
			(stroke
				(width 0)
				(type default)
			)
			(fill no)
			(layer "B.Fab")
		)
		(pad "1" smd custom
			(at 0 -0.4445 270)
			(size 0.1397 0.1397)
			(layers "B.Cu" "B.Mask" "B.Paste")
			(net "P12V_STBY_SCC")
			(options
				(clearance outline)
				(anchor circle)
			)
			(primitives
				(gr_poly
					(pts
						(arc
							(start -0.1778 0.2794)
							(mid -0.249642 0.249642)
							(end -0.2794 0.1778)
						)
						(arc
							(start -0.2794 -0.1778)
							(mid -0.249642 -0.249642)
							(end -0.1778 -0.2794)
						)
						(arc
							(start 0.1778 -0.2794)
							(mid 0.249642 -0.249642)
							(end 0.2794 -0.1778)
						)
						(arc
							(start 0.2794 0.1778)
							(mid 0.249642 0.249642)
							(end 0.1778 0.2794)
						)
					)
					(width 0)
					(fill yes)
				)
			)
		)
		(pad "2" smd custom
			(at 0 0.4445 270)
			(size 0.1397 0.1397)
			(layers "B.Cu" "B.Mask" "B.Paste")
			(net "P1V5_C_PG_G")
			(options
				(clearance outline)
				(anchor circle)
			)
			(primitives
				(gr_poly
					(pts
						(arc
							(start -0.1778 0.2794)
							(mid -0.249642 0.249642)
							(end -0.2794 0.1778)
						)
						(arc
							(start -0.2794 -0.1778)
							(mid -0.249642 -0.249642)
							(end -0.1778 -0.2794)
						)
						(arc
							(start 0.1778 -0.2794)
							(mid 0.249642 -0.249642)
							(end 0.2794 -0.1778)
						)
						(arc
							(start 0.2794 0.1778)
							(mid 0.249642 0.249642)
							(end 0.1778 0.2794)
						)
					)
					(width 0)
					(fill yes)
				)
			)
		)
	)
)
